(kicad_pcb
	(version 20260206)
	(generator "pcbnew")
	(generator_version "10.0")
	(general
		(thickness 1.6)
		(legacy_teardrops no)
	)
	(paper "A4")
	(title_block
		(title "peb — Lightning_PEB_BRD.brd")
		(comment 1 "Lightning (Wiwynn / Facebook NVMe JBOF) / footprints 967-975 of 2563")
	)
	(layers
		(0 "F.Cu" signal "TOP")
		(4 "In1.Cu" signal "L2GND")
		(6 "In2.Cu" signal "L3")
		(8 "In3.Cu" signal "L4VCC")
		(10 "In4.Cu" signal "L5VCC")
		(12 "In5.Cu" signal "L6")
		(14 "In6.Cu" signal "L7GND")
		(2 "B.Cu" signal "BOTTOM")
		(9 "F.Adhes" user "F.Adhesive")
		(11 "B.Adhes" user "B.Adhesive")
		(13 "F.Paste" user "Package Geometry/Pastemask Top")
		(15 "B.Paste" user "Package Geometry/Pastemask Bottom")
		(5 "F.SilkS" user "Ref Des/Silkscreen Top")
		(7 "B.SilkS" user "Ref Des/Silkscreen Bottom")
		(1 "F.Mask" user "Board Geometry/Soldermask Top")
		(3 "B.Mask" user "Board Geometry/Soldermask Bottom")
		(17 "Dwgs.User" user "User.Drawings")
		(19 "Cmts.User" user "User.Comments")
		(21 "Eco1.User" user "User.Eco1")
		(23 "Eco2.User" user "User.Eco2")
		(25 "Edge.Cuts" user "Board Geometry/Outline")
		(27 "Margin" user)
		(31 "F.CrtYd" user "Package Geometry/Place Bound Top")
		(29 "B.CrtYd" user "Package Geometry/Place Bound Bottom")
		(35 "F.Fab" user "Ref Des/Assembly Top")
		(33 "B.Fab" user "Ref Des/Assembly Bottom")
	)
	(footprint ""
		(layer "F.Cu")
		(at 187.2234 -28.96108 90)
		(property "Reference" "R666"
			(at 0 0 90)
			(layer "F.SilkS")
			(hide yes)
			(effects
				(font
					(size 1.27 1.27)
				)
			)
		)
		(property "Value" "0R2J-2-GP"
			(at 0.064008 -3.993896 90)
			(unlocked yes)
			(layer "F.Fab")
			(hide yes)
			(effects
				(font
					(size 1.016 1.016)
					(thickness 0.1524)
				)
			)
		)
		(property "Device Type" "R402H16"
			(at 0.064008 -5.517896 90)
			(unlocked yes)
			(layer "F.Fab")
			(hide yes)
			(effects
				(font
					(size 1.016 1.016)
					(thickness 0.1524)
				)
			)
		)
		(duplicate_pad_numbers_are_jumpers no)
		(fp_line
			(start 0.508 -0.9398)
			(end -0.508 -0.9398)
			(stroke
				(width 0.1524)
				(type default)
			)
			(layer "F.SilkS")
		)
		(fp_line
			(start -0.508 -0.9398)
			(end -0.508 0.9398)
			(stroke
				(width 0.1524)
				(type default)
			)
			(layer "F.SilkS")
		)
		(fp_rect
			(start -0.508 0.9398)
			(end 0.508 -0.9398)
			(stroke
				(width 0)
				(type default)
			)
			(fill no)
			(layer "F.CrtYd")
		)
		(fp_rect
			(start -0.508 0.9398)
			(end 0.508 -0.9398)
			(stroke
				(width 0)
				(type default)
			)
			(fill no)
			(layer "F.Fab")
		)
		(pad "1" smd custom
			(at 0 -0.4445 90)
			(size 0.1397 0.1397)
			(layers "F.Cu" "F.Mask" "F.Paste")
			(net "8644_USB_DN4")
			(options
				(clearance outline)
				(anchor circle)
			)
			(primitives
				(gr_poly
					(pts
						(arc
							(start -0.1778 -0.2794)
							(mid -0.249642 -0.249642)
							(end -0.2794 -0.1778)
						)
						(arc
							(start -0.2794 0.1778)
							(mid -0.249642 0.249642)
							(end -0.1778 0.2794)
						)
						(arc
							(start 0.1778 0.2794)
							(mid 0.249642 0.249642)
							(end 0.2794 0.1778)
						)
						(arc
							(start 0.2794 -0.1778)
							(mid 0.249642 -0.249642)
							(end 0.1778 -0.2794)
						)
					)
					(width 0)
					(fill yes)
				)
			)
		)
		(pad "2" smd custom
			(at 0 0.4445 90)
			(size 0.1397 0.1397)
			(layers "F.Cu" "F.Mask" "F.Paste")
			(net "P3V3_STBY")
			(options
				(clearance outline)
				(anchor circle)
			)
			(primitives
				(gr_poly
					(pts
						(arc
							(start -0.1778 -0.2794)
							(mid -0.249642 -0.249642)
							(end -0.2794 -0.1778)
						)
						(arc
							(start -0.2794 0.1778)
							(mid -0.249642 0.249642)
							(end -0.1778 0.2794)
						)
						(arc
							(start 0.1778 0.2794)
							(mid 0.249642 0.249642)
							(end 0.2794 0.1778)
						)
						(arc
							(start 0.2794 -0.1778)
							(mid 0.249642 -0.249642)
							(end 0.1778 -0.2794)
						)
					)
					(width 0)
					(fill yes)
				)
			)
		)
	)
	(footprint ""
		(layer "F.Cu")
		(at 200.6219 -59.99988)
		(property "Reference" "PAD4"
			(at 0 0 0)
			(layer "F.SilkS")
			(hide yes)
			(effects
				(font
					(size 1.27 1.27)
				)
			)
		)
		(property "Value" "PAD-2P-21-GP"
			(at 7.164832 -10.8712 0)
			(unlocked yes)
			(layer "F.Fab")
			(hide yes)
			(effects
				(font
					(size 1.016 1.016)
					(thickness 0.1524)
				)
			)
		)
		(property "Device Type" "HT12X22B8R32-2P-S"
			(at 7.164832 -12.3952 0)
			(unlocked yes)
			(layer "F.Fab")
			(hide yes)
			(effects
				(font
					(size 1.016 1.016)
					(thickness 0.1524)
				)
			)
		)
		(duplicate_pad_numbers_are_jumpers no)
		(fp_poly
			(pts
				(arc
					(start 4.3053 -11.999976)
					(mid -4.3053 -11.999976)
					(end 4.3053 -11.999976)
				)
			)
			(stroke
				(width 0)
				(type default)
			)
			(fill no)
			(layer "B.CrtYd")
		)
		(fp_poly
			(pts
				(arc
					(start 4.3053 0)
					(mid -4.3053 0)
					(end 4.3053 0)
				)
			)
			(stroke
				(width 0)
				(type default)
			)
			(fill no)
			(layer "B.CrtYd")
		)
		(fp_rect
			(start -7.2898 5.3086)
			(end 5.3086 -17.2974)
			(stroke
				(width 0)
				(type default)
			)
			(fill no)
			(layer "F.CrtYd")
		)
		(fp_poly
			(pts
				(arc
					(start 4.3053 -11.999976)
					(mid -4.3053 -11.999976)
					(end 4.3053 -11.999976)
				)
			)
			(stroke
				(width 0)
				(type default)
			)
			(fill no)
			(layer "B.Fab")
		)
		(fp_poly
			(pts
				(arc
					(start 4.3053 0)
					(mid -4.3053 0)
					(end 4.3053 0)
				)
			)
			(stroke
				(width 0)
				(type default)
			)
			(fill no)
			(layer "B.Fab")
		)
		(fp_rect
			(start -7.2898 5.3086)
			(end 5.3086 -17.2974)
			(stroke
				(width 0)
				(type default)
			)
			(fill no)
			(layer "F.Fab")
		)
		(pad "1" thru_hole rect
			(at 0 0)
			(size 11.9888 21.9964)
			(drill 3.2004
				(offset -0.9906 -5.9944)
			)
			(layers "*.Cu" "*.Mask")
			(remove_unused_layers no)
			(net "GND")
			(clearance -3.8862)
			(thermal_gap 0.3048)
			(padstack
				(mode front_inner_back)
				(layer "Inner"
					(shape circle)
					(size 3.6068 3.6068)
					(clearance 0.3048)
				)
				(layer "B.Cu"
					(shape circle)
					(size 8.001 8.001)
					(clearance -1.8923)
				)
			)
		)
		(pad "2" thru_hole circle
			(at 0 -11.999976)
			(size 8.001 8.001)
			(drill 3.2004)
			(layers "*.Cu" "*.Mask")
			(remove_unused_layers no)
			(net "GND")
			(clearance -1.8923)
			(thermal_gap 0.3048)
			(padstack
				(mode front_inner_back)
				(layer "Inner"
					(shape circle)
					(size 3.6068 3.6068)
					(clearance 0.3048)
				)
				(layer "B.Cu"
					(shape circle)
					(size 8.001 8.001)
					(clearance -1.8923)
				)
			)
		)
	)
	(footprint ""
		(layer "F.Cu")
		(at 146.2532 -83.7946 -90)
		(property "Reference" "PG33"
			(at 0 0 270)
			(layer "F.SilkS")
			(hide yes)
			(effects
				(font
					(size 1.27 1.27)
				)
			)
		)
		(property "Value" "GAP-CLOSE-PWR-3-GP"
			(at 0.0254 -6.5786 270)
			(unlocked yes)
			(layer "F.Fab")
			(hide yes)
			(effects
				(font
					(size 1.016 1.016)
					(thickness 0.1524)
				)
			)
		)
		(property "Device Type" "GAP-CLOSE-PWR-3"
			(at 0.0254 -8.255 270)
			(unlocked yes)
			(layer "F.Fab")
			(hide yes)
			(effects
				(font
					(size 1.016 1.016)
					(thickness 0.1524)
				)
			)
		)
		(duplicate_pad_numbers_are_jumpers no)
		(fp_rect
			(start -0.7112 0.4572)
			(end 0.7112 -0.4572)
			(stroke
				(width 0)
				(type default)
			)
			(fill no)
			(layer "F.CrtYd")
		)
		(fp_poly
			(pts
				(xy -0.7112 -0.4572) (xy 0.7112 -0.4572) (xy 0.7112 0.4572) (xy -0.7112 0.4572)
			)
			(stroke
				(width 0)
				(type default)
			)
			(fill no)
			(layer "F.Fab")
		)
		(pad "1" smd rect
			(at -0.3048 0 270)
			(size 0.6604 0.762)
			(layers "F.Cu" "F.Mask" "F.Paste")
			(net "P1V8_PWR")
		)
		(pad "2" smd rect
			(at 0.3048 0 270)
			(size 0.6604 0.762)
			(layers "F.Cu" "F.Mask" "F.Paste")
			(net "DUT_VDDO")
		)
	)
	(footprint ""
		(layer "F.Cu")
		(at 38.689026 -146.48688)
		(property "Reference" "C178"
			(at 0 0 0)
			(layer "F.SilkS")
			(hide yes)
			(effects
				(font
					(size 1.27 1.27)
				)
			)
		)
		(property "Value" "SCD1U16V2KX-3GP"
			(at 1.1811 -2.7051 0)
			(unlocked yes)
			(layer "F.Fab")
			(hide yes)
			(effects
				(font
					(size 1.016 1.016)
					(thickness 0.1524)
				)
			)
		)
		(property "Device Type" "C402H22"
			(at 1.1811 -4.2291 0)
			(unlocked yes)
			(layer "F.Fab")
			(hide yes)
			(effects
				(font
					(size 1.016 1.016)
					(thickness 0.1524)
				)
			)
		)
		(duplicate_pad_numbers_are_jumpers no)
		(fp_rect
			(start -0.4318 0.9525)
			(end 0.4318 -0.9525)
			(stroke
				(width 0)
				(type default)
			)
			(fill no)
			(layer "F.CrtYd")
		)
		(fp_rect
			(start -0.4318 0.9525)
			(end 0.4318 -0.9525)
			(stroke
				(width 0)
				(type default)
			)
			(fill no)
			(layer "F.Fab")
		)
		(pad "1" smd custom
			(at 0 -0.4445)
			(size 0.1524 0.1524)
			(layers "F.Cu" "F.Mask" "F.Paste")
			(net "P1V53_STBY")
			(options
				(clearance outline)
				(anchor circle)
			)
			(primitives
				(gr_poly
					(pts
						(arc
							(start 0.3048 -0.2032)
							(mid 0.275042 -0.275042)
							(end 0.2032 -0.3048)
						)
						(arc
							(start -0.2032 -0.3048)
							(mid -0.275042 -0.275042)
							(end -0.3048 -0.2032)
						)
						(arc
							(start -0.3048 0.2032)
							(mid -0.275042 0.275042)
							(end -0.2032 0.3048)
						)
						(arc
							(start 0.2032 0.3048)
							(mid 0.275042 0.275042)
							(end 0.3048 0.2032)
						)
					)
					(width 0)
					(fill yes)
				)
			)
		)
		(pad "2" smd custom
			(at 0 0.4445)
			(size 0.1524 0.1524)
			(layers "F.Cu" "F.Mask" "F.Paste")
			(net "GND")
			(options
				(clearance outline)
				(anchor circle)
			)
			(primitives
				(gr_poly
					(pts
						(arc
							(start 0.3048 -0.2032)
							(mid 0.275042 -0.275042)
							(end 0.2032 -0.3048)
						)
						(arc
							(start -0.2032 -0.3048)
							(mid -0.275042 -0.275042)
							(end -0.3048 -0.2032)
						)
						(arc
							(start -0.3048 0.2032)
							(mid -0.275042 0.275042)
							(end -0.2032 0.3048)
						)
						(arc
							(start 0.2032 0.3048)
							(mid 0.275042 0.275042)
							(end 0.3048 0.2032)
						)
					)
					(width 0)
					(fill yes)
				)
			)
		)
	)
	(footprint ""
		(layer "F.Cu")
		(at 333.502 -74.041 180)
		(property "Reference" "PR156"
			(at 0 0 180)
			(layer "F.SilkS")
			(hide yes)
			(effects
				(font
					(size 1.27 1.27)
				)
			)
		)
		(property "Value" "10D7R2F-GP"
			(at 0.064008 -3.993896 180)
			(unlocked yes)
			(layer "F.Fab")
			(hide yes)
			(effects
				(font
					(size 1.016 1.016)
					(thickness 0.1524)
				)
			)
		)
		(property "Device Type" "R402H16"
			(at 0.064008 -5.517896 180)
			(unlocked yes)
			(layer "F.Fab")
			(hide yes)
			(effects
				(font
					(size 1.016 1.016)
					(thickness 0.1524)
				)
			)
		)
		(duplicate_pad_numbers_are_jumpers no)
		(fp_line
			(start 0.508 -0.9398)
			(end -0.508 -0.9398)
			(stroke
				(width 0.1524)
				(type default)
			)
			(layer "F.SilkS")
		)
		(fp_line
			(start -0.508 -0.9398)
			(end -0.508 0.9398)
			(stroke
				(width 0.1524)
				(type default)
			)
			(layer "F.SilkS")
		)
		(fp_rect
			(start -0.508 0.9398)
			(end 0.508 -0.9398)
			(stroke
				(width 0)
				(type default)
			)
			(fill no)
			(layer "F.CrtYd")
		)
		(fp_rect
			(start -0.508 0.9398)
			(end 0.508 -0.9398)
			(stroke
				(width 0)
				(type default)
			)
			(fill no)
			(layer "F.Fab")
		)
		(pad "1" smd custom
			(at 0 -0.4445 180)
			(size 0.1397 0.1397)
			(layers "F.Cu" "F.Mask" "F.Paste")
			(net "P0V9_E_VFB_R")
			(options
				(clearance outline)
				(anchor circle)
			)
			(primitives
				(gr_poly
					(pts
						(arc
							(start -0.1778 -0.2794)
							(mid -0.249642 -0.249642)
							(end -0.2794 -0.1778)
						)
						(arc
							(start -0.2794 0.1778)
							(mid -0.249642 0.249642)
							(end -0.1778 0.2794)
						)
						(arc
							(start 0.1778 0.2794)
							(mid 0.249642 0.249642)
							(end 0.2794 0.1778)
						)
						(arc
							(start 0.2794 -0.1778)
							(mid 0.249642 -0.249642)
							(end 0.1778 -0.2794)
						)
					)
					(width 0)
					(fill yes)
				)
			)
		)
		(pad "2" smd custom
			(at 0 0.4445 180)
			(size 0.1397 0.1397)
			(layers "F.Cu" "F.Mask" "F.Paste")
			(net "P0V9_E")
			(options
				(clearance outline)
				(anchor circle)
			)
			(primitives
				(gr_poly
					(pts
						(arc
							(start -0.1778 -0.2794)
							(mid -0.249642 -0.249642)
							(end -0.2794 -0.1778)
						)
						(arc
							(start -0.2794 0.1778)
							(mid -0.249642 0.249642)
							(end -0.1778 0.2794)
						)
						(arc
							(start 0.1778 0.2794)
							(mid 0.249642 0.249642)
							(end 0.2794 0.1778)
						)
						(arc
							(start 0.2794 -0.1778)
							(mid 0.249642 -0.249642)
							(end 0.1778 -0.2794)
						)
					)
					(width 0)
					(fill yes)
				)
			)
		)
	)
	(footprint ""
		(layer "F.Cu")
		(at 227.711 -3.81 180)
		(property "Reference" "R85"
			(at 0 0 180)
			(layer "F.SilkS")
			(hide yes)
			(effects
				(font
					(size 1.27 1.27)
				)
			)
		)
		(property "Value" "150R2F-1-GP"
			(at 0.064008 -3.993896 180)
			(unlocked yes)
			(layer "F.Fab")
			(hide yes)
			(effects
				(font
					(size 1.016 1.016)
					(thickness 0.1524)
				)
			)
		)
		(property "Device Type" "R402H16"
			(at 0.064008 -5.517896 180)
			(unlocked yes)
			(layer "F.Fab")
			(hide yes)
			(effects
				(font
					(size 1.016 1.016)
					(thickness 0.1524)
				)
			)
		)
		(duplicate_pad_numbers_are_jumpers no)
		(fp_line
			(start 0.508 -0.9398)
			(end -0.508 -0.9398)
			(stroke
				(width 0.1524)
				(type default)
			)
			(layer "F.SilkS")
		)
		(fp_line
			(start -0.508 -0.9398)
			(end -0.508 0.9398)
			(stroke
				(width 0.1524)
				(type default)
			)
			(layer "F.SilkS")
		)
		(fp_rect
			(start -0.508 0.9398)
			(end 0.508 -0.9398)
			(stroke
				(width 0)
				(type default)
			)
			(fill no)
			(layer "F.CrtYd")
		)
		(fp_rect
			(start -0.508 0.9398)
			(end 0.508 -0.9398)
			(stroke
				(width 0)
				(type default)
			)
			(fill no)
			(layer "F.Fab")
		)
		(pad "1" smd custom
			(at 0 -0.4445 180)
			(size 0.1397 0.1397)
			(layers "F.Cu" "F.Mask" "F.Paste")
			(net "P3V3_STBY")
			(options
				(clearance outline)
				(anchor circle)
			)
			(primitives
				(gr_poly
					(pts
						(arc
							(start -0.1778 -0.2794)
							(mid -0.249642 -0.249642)
							(end -0.2794 -0.1778)
						)
						(arc
							(start -0.2794 0.1778)
							(mid -0.249642 0.249642)
							(end -0.1778 0.2794)
						)
						(arc
							(start 0.1778 0.2794)
							(mid 0.249642 0.249642)
							(end 0.2794 0.1778)
						)
						(arc
							(start 0.2794 -0.1778)
							(mid 0.249642 -0.249642)
							(end 0.1778 -0.2794)
						)
					)
					(width 0)
					(fill yes)
				)
			)
		)
		(pad "2" smd custom
			(at 0 0.4445 180)
			(size 0.1397 0.1397)
			(layers "F.Cu" "F.Mask" "F.Paste")
			(net "CONSOLE_LED_0")
			(options
				(clearance outline)
				(anchor circle)
			)
			(primitives
				(gr_poly
					(pts
						(arc
							(start -0.1778 -0.2794)
							(mid -0.249642 -0.249642)
							(end -0.2794 -0.1778)
						)
						(arc
							(start -0.2794 0.1778)
							(mid -0.249642 0.249642)
							(end -0.1778 0.2794)
						)
						(arc
							(start 0.1778 0.2794)
							(mid 0.249642 0.249642)
							(end 0.2794 0.1778)
						)
						(arc
							(start 0.2794 -0.1778)
							(mid 0.249642 -0.249642)
							(end 0.1778 -0.2794)
						)
					)
					(width 0)
					(fill yes)
				)
			)
		)
	)
	(footprint ""
		(layer "F.Cu")
		(at 178.1048 -67.691 180)
		(property "Reference" "PG28"
			(at 0 0 180)
			(layer "F.SilkS")
			(hide yes)
			(effects
				(font
					(size 1.27 1.27)
				)
			)
		)
		(property "Value" "GAP-CLOSE-PWR-3-GP"
			(at 0.0254 -6.5786 180)
			(unlocked yes)
			(layer "F.Fab")
			(hide yes)
			(effects
				(font
					(size 1.016 1.016)
					(thickness 0.1524)
				)
			)
		)
		(property "Device Type" "GAP-CLOSE-PWR-3"
			(at 0.0254 -8.255 180)
			(unlocked yes)
			(layer "F.Fab")
			(hide yes)
			(effects
				(font
					(size 1.016 1.016)
					(thickness 0.1524)
				)
			)
		)
		(duplicate_pad_numbers_are_jumpers no)
		(fp_rect
			(start -0.7112 0.4572)
			(end 0.7112 -0.4572)
			(stroke
				(width 0)
				(type default)
			)
			(fill no)
			(layer "F.CrtYd")
		)
		(fp_poly
			(pts
				(xy -0.7112 -0.4572) (xy 0.7112 -0.4572) (xy 0.7112 0.4572) (xy -0.7112 0.4572)
			)
			(stroke
				(width 0)
				(type default)
			)
			(fill no)
			(layer "F.Fab")
		)
		(pad "1" smd rect
			(at -0.3048 0 180)
			(size 0.6604 0.762)
			(layers "F.Cu" "F.Mask" "F.Paste")
			(net "DUT_AVD_PCIE")
		)
		(pad "2" smd rect
			(at 0.3048 0 180)
			(size 0.6604 0.762)
			(layers "F.Cu" "F.Mask" "F.Paste")
			(net "P0V9")
		)
	)
	(footprint ""
		(layer "F.Cu")
		(at 43.379136 -46.148244 -90)
		(property "Reference" "R409"
			(at 0 0 270)
			(layer "F.SilkS")
			(hide yes)
			(effects
				(font
					(size 1.27 1.27)
				)
			)
		)
		(property "Value" "0R2J-2-GP"
			(at 0.064008 -3.993896 270)
			(unlocked yes)
			(layer "F.Fab")
			(hide yes)
			(effects
				(font
					(size 1.016 1.016)
					(thickness 0.1524)
				)
			)
		)
		(property "Device Type" "R402H16"
			(at 0.064008 -5.517896 270)
			(unlocked yes)
			(layer "F.Fab")
			(hide yes)
			(effects
				(font
					(size 1.016 1.016)
					(thickness 0.1524)
				)
			)
		)
		(duplicate_pad_numbers_are_jumpers no)
		(fp_line
			(start -0.508 -0.9398)
			(end -0.508 0.9398)
			(stroke
				(width 0.1524)
				(type default)
			)
			(layer "F.SilkS")
		)
		(fp_line
			(start 0.508 -0.9398)
			(end -0.508 -0.9398)
			(stroke
				(width 0.1524)
				(type default)
			)
			(layer "F.SilkS")
		)
		(fp_rect
			(start -0.508 0.9398)
			(end 0.508 -0.9398)
			(stroke
				(width 0)
				(type default)
			)
			(fill no)
			(layer "F.CrtYd")
		)
		(fp_rect
			(start -0.508 0.9398)
			(end 0.508 -0.9398)
			(stroke
				(width 0)
				(type default)
			)
			(fill no)
			(layer "F.Fab")
		)
		(pad "1" smd custom
			(at 0 -0.4445 270)
			(size 0.1397 0.1397)
			(layers "F.Cu" "F.Mask" "F.Paste")
			(net "USB_DP_R")
			(options
				(clearance outline)
				(anchor circle)
			)
			(primitives
				(gr_poly
					(pts
						(arc
							(start -0.1778 -0.2794)
							(mid -0.249642 -0.249642)
							(end -0.2794 -0.1778)
						)
						(arc
							(start -0.2794 0.1778)
							(mid -0.249642 0.249642)
							(end -0.1778 0.2794)
						)
						(arc
							(start 0.1778 0.2794)
							(mid 0.249642 0.249642)
							(end 0.2794 0.1778)
						)
						(arc
							(start 0.2794 -0.1778)
							(mid 0.249642 -0.249642)
							(end 0.1778 -0.2794)
						)
					)
					(width 0)
					(fill yes)
				)
			)
		)
		(pad "2" smd custom
			(at 0 0.4445 270)
			(size 0.1397 0.1397)
			(layers "F.Cu" "F.Mask" "F.Paste")
			(net "USB_P1_F_DP1")
			(options
				(clearance outline)
				(anchor circle)
			)
			(primitives
				(gr_poly
					(pts
						(arc
							(start -0.1778 -0.2794)
							(mid -0.249642 -0.249642)
							(end -0.2794 -0.1778)
						)
						(arc
							(start -0.2794 0.1778)
							(mid -0.249642 0.249642)
							(end -0.1778 0.2794)
						)
						(arc
							(start 0.1778 0.2794)
							(mid 0.249642 0.249642)
							(end 0.2794 0.1778)
						)
						(arc
							(start 0.2794 -0.1778)
							(mid 0.249642 -0.249642)
							(end 0.1778 -0.2794)
						)
					)
					(width 0)
					(fill yes)
				)
			)
		)
	)
	(footprint ""
		(layer "F.Cu")
		(at 160.528 -97.5614 90)
		(property "Reference" "TP77"
			(at 0 0 90)
			(layer "F.SilkS")
			(hide yes)
			(effects
				(font
					(size 1.27 1.27)
				)
			)
		)
		(property "Value" "TPAD28-2-GP"
			(at -0.0127 -1.6637 90)
			(unlocked yes)
			(layer "F.Fab")
			(hide yes)
			(effects
				(font
					(size 1.016 1.016)
					(thickness 0.1524)
				)
			)
		)
		(property "Device Type" "TPAD28"
			(at -0.0127 -3.1877 90)
			(unlocked yes)
			(layer "F.Fab")
			(hide yes)
			(effects
				(font
					(size 1.016 1.016)
					(thickness 0.1524)
				)
			)
		)
		(duplicate_pad_numbers_are_jumpers no)
		(fp_poly
			(pts
				(arc
					(start 0 0.3556)
					(mid 0 -0.3556)
					(end 0 0.3556)
				)
			)
			(stroke
				(width 0)
				(type default)
			)
			(fill no)
			(layer "F.CrtYd")
		)
		(fp_poly
			(pts
				(arc
					(start 0 0.6096)
					(mid 0 -0.6096)
					(end 0 0.6096)
				)
			)
			(stroke
				(width 0)
				(type default)
			)
			(fill no)
			(layer "F.Fab")
		)
		(pad "1" smd circle
			(at 0 0 90)
			(size 0.7112 0.7112)
			(layers "F.Cu" "F.Mask" "F.Paste")
			(net "CLKGEN_OE3")
		)
	)
)
